# S9S_MB_2U (Grand Teton) — schematic netlist excerpt (pin names and nets, part order shuffled) for the footprints in the layout excerpt that follows; sources: Cadence DE-HDL packaged netlist, KiCad conversion of 03242023_DA0F0TMBIJ0_F0T_Motherboard_J_brd_V01_OCP.brd

C1178  Q_CAP  22UF 4V 20% X6S  pkg C0603  page 189 : A = P1V05_PCH_AUX ; B = GND
R953  Q_RES  4.75K 1% CHIP  pkg 0402LF  page 208 : A = CLK_CK440_SMB_ADDR0 ; B = GND

(kicad_pcb
	(version 20260206)
	(generator "pcbnew")
	(generator_version "10.0")
	(general
		(thickness 1.6)
		(legacy_teardrops no)
	)
	(paper "A4")
	(title_block
		(title "03242023_DA0F0TMBIJ0_F0T_Motherboard_J_brd_V01_OCP.brd")
		(comment 1 "Grand Teton / footprints 5028-5029 of 6105")
	)
	(layers
		(0 "F.Cu" signal "TOP")
		(4 "In1.Cu" signal "GND")
		(6 "In2.Cu" signal "IN1")
		(8 "In3.Cu" signal "GND1")
		(10 "In4.Cu" signal "IN2")
		(12 "In5.Cu" signal "GND2")
		(14 "In6.Cu" signal "IN3")
		(16 "In7.Cu" signal "GND3")
		(18 "In8.Cu" signal "VCC")
		(20 "In9.Cu" signal "VCC1")
		(22 "In10.Cu" signal "GND4")
		(24 "In11.Cu" signal "IN4")
		(26 "In12.Cu" signal "GND5")
		(28 "In13.Cu" signal "IN5")
		(30 "In14.Cu" signal "GND6")
		(32 "In15.Cu" signal "IN6")
		(34 "In16.Cu" signal "GND7")
		(2 "B.Cu" signal "BOTTOM")
		(9 "F.Adhes" user "F.Adhesive")
		(11 "B.Adhes" user "B.Adhesive")
		(13 "F.Paste" user "Package Geometry/Pastemask Top")
		(15 "B.Paste" user "Package Geometry/Pastemask Bottom")
		(5 "F.SilkS" user "Ref Des/Silkscreen Top")
		(7 "B.SilkS" user "Ref Des/Silkscreen Bottom")
		(1 "F.Mask" user "Board Geometry/Soldermask Top")
		(3 "B.Mask" user "Board Geometry/Soldermask Bottom")
		(17 "Dwgs.User" user "User.Drawings")
		(19 "Cmts.User" user "User.Comments")
		(21 "Eco1.User" user "User.Eco1")
		(23 "Eco2.User" user "User.Eco2")
		(25 "Edge.Cuts" user "Board Geometry/Outline")
		(27 "Margin" user)
		(31 "F.CrtYd" user "Package Geometry/Place Bound Top")
		(29 "B.CrtYd" user "Package Geometry/Place Bound Bottom")
		(35 "F.Fab" user "Ref Des/Assembly Top")
		(33 "B.Fab" user "Ref Des/Assembly Bottom")
	)
	(footprint ""
		(layer "B.Cu")
		(at 245.835424 -99.136708)
		(property "Reference" "R953"
			(at 0 0 0)
			(layer "B.SilkS")
			(hide yes)
			(effects
				(font
					(size 1.27 1.27)
				)
				(justify mirror)
			)
		)
		(property "Value" ""
			(at 0 0 0)
			(layer "B.Fab")
			(effects
				(font
					(size 1.27 1.27)
				)
				(justify mirror)
			)
		)
		(duplicate_pad_numbers_are_jumpers no)
		(fp_line
			(start -0.7874 -0.4064)
			(end -0.7874 0.4064)
			(stroke
				(width 0.1524)
				(type default)
			)
			(layer "B.SilkS")
		)
		(fp_line
			(start -0.7874 0.4064)
			(end 0.7874 0.4064)
			(stroke
				(width 0.1524)
				(type default)
			)
			(layer "B.SilkS")
		)
		(fp_line
			(start 0.7874 -0.4064)
			(end -0.7874 -0.4064)
			(stroke
				(width 0.1524)
				(type default)
			)
			(layer "B.SilkS")
		)
		(fp_line
			(start 0.7874 0.4064)
			(end 0.7874 -0.4064)
			(stroke
				(width 0.1524)
				(type default)
			)
			(layer "B.SilkS")
		)
		(fp_line
			(start -0.67945 -0.3048)
			(end -0.67945 0.3048)
			(stroke
				(width 0.1)
				(type default)
			)
			(layer "B.Fab")
		)
		(fp_line
			(start -0.67945 0.3048)
			(end -0.120396 0.3048)
			(stroke
				(width 0.1)
				(type default)
			)
			(layer "B.Fab")
		)
		(fp_line
			(start -0.12065 -0.3048)
			(end -0.67945 -0.3048)
			(stroke
				(width 0.1)
				(type default)
			)
			(layer "B.Fab")
		)
		(fp_line
			(start -0.12065 -0.2794)
			(end -0.12065 -0.3048)
			(stroke
				(width 0.1)
				(type default)
			)
			(layer "B.Fab")
		)
		(fp_line
			(start -0.120396 0.2794)
			(end 0.12065 0.2794)
			(stroke
				(width 0.1)
				(type default)
			)
			(layer "B.Fab")
		)
		(fp_line
			(start -0.120396 0.3048)
			(end -0.120396 0.2794)
			(stroke
				(width 0.1)
				(type default)
			)
			(layer "B.Fab")
		)
		(fp_line
			(start 0.12065 -0.305054)
			(end 0.12065 -0.2794)
			(stroke
				(width 0.1)
				(type default)
			)
			(layer "B.Fab")
		)
		(fp_line
			(start 0.12065 -0.2794)
			(end -0.12065 -0.2794)
			(stroke
				(width 0.1)
				(type default)
			)
			(layer "B.Fab")
		)
		(fp_line
			(start 0.12065 0.2794)
			(end 0.12065 0.3048)
			(stroke
				(width 0.1)
				(type default)
			)
			(layer "B.Fab")
		)
		(fp_line
			(start 0.12065 0.3048)
			(end 0.67945 0.3048)
			(stroke
				(width 0.1)
				(type default)
			)
			(layer "B.Fab")
		)
		(fp_line
			(start 0.67945 -0.305054)
			(end 0.12065 -0.305054)
			(stroke
				(width 0.1)
				(type default)
			)
			(layer "B.Fab")
		)
		(fp_line
			(start 0.67945 0.3048)
			(end 0.67945 -0.305054)
			(stroke
				(width 0.1)
				(type default)
			)
			(layer "B.Fab")
		)
		(pad "1" smd circle
			(at 0.40005 0 180)
			(size 0 0)
			(layers "B.Cu" "B.Mask" "B.Paste")
			(net "CLK_CK440_SMB_ADDR0")
		)
		(pad "2" smd circle
			(at -0.40005 0 180)
			(size 0 0)
			(layers "B.Cu" "B.Mask" "B.Paste")
			(net "GND")
		)
	)
	(footprint ""
		(layer "B.Cu")
		(at 302.218852 -53.018182 180)
		(property "Reference" "C1178"
			(at 0 0 0)
			(layer "B.SilkS")
			(hide yes)
			(effects
				(font
					(size 1.27 1.27)
				)
				(justify mirror)
			)
		)
		(property "Value" ""
			(at 0 0 0)
			(layer "B.Fab")
			(effects
				(font
					(size 1.27 1.27)
				)
				(justify mirror)
			)
		)
		(duplicate_pad_numbers_are_jumpers no)
		(fp_line
			(start 1.2954 0.5842)
			(end 1.2954 -0.5842)
			(stroke
				(width 0.1524)
				(type default)
			)
			(layer "B.SilkS")
		)
		(fp_line
			(start 1.2954 -0.5842)
			(end -1.2954 -0.5842)
			(stroke
				(width 0.1524)
				(type default)
			)
			(layer "B.SilkS")
		)
		(fp_line
			(start 0 -0.5842)
			(end 0 0.5842)
			(stroke
				(width 0.1524)
				(type default)
			)
			(layer "B.SilkS")
		)
		(fp_line
			(start -1.2954 0.5842)
			(end 1.2954 0.5842)
			(stroke
				(width 0.1524)
				(type default)
			)
			(layer "B.SilkS")
		)
		(fp_line
			(start -1.2954 -0.5842)
			(end -1.2954 0.5842)
			(stroke
				(width 0.1524)
				(type default)
			)
			(layer "B.SilkS")
		)
		(fp_line
			(start 1.1938 0.4064)
			(end 1.1938 -0.4064)
			(stroke
				(width 0.1)
				(type default)
			)
			(layer "B.Fab")
		)
		(fp_line
			(start 1.1938 -0.4064)
			(end 0.8636 -0.4064)
			(stroke
				(width 0.1)
				(type default)
			)
			(layer "B.Fab")
		)
		(fp_line
			(start 0.8636 0.4572)
			(end 0.8636 0.4064)
			(stroke
				(width 0.1)
				(type default)
			)
			(layer "B.Fab")
		)
		(fp_line
			(start 0.8636 0.4064)
			(end 1.1938 0.4064)
			(stroke
				(width 0.1)
				(type default)
			)
			(layer "B.Fab")
		)
		(fp_line
			(start 0.8636 -0.4064)
			(end 0.8636 -0.4572)
			(stroke
				(width 0.1)
				(type default)
			)
			(layer "B.Fab")
		)
		(fp_line
			(start 0.8636 -0.4572)
			(end -0.8636 -0.4572)
			(stroke
				(width 0.1)
				(type default)
			)
			(layer "B.Fab")
		)
		(fp_line
			(start -0.8636 0.4572)
			(end 0.8636 0.4572)
			(stroke
				(width 0.1)
				(type default)
			)
			(layer "B.Fab")
		)
		(fp_line
			(start -0.8636 0.4064)
			(end -0.8636 0.4572)
			(stroke
				(width 0.1)
				(type default)
			)
			(layer "B.Fab")
		)
		(fp_line
			(start -0.8636 -0.4064)
			(end -1.1938 -0.4064)
			(stroke
				(width 0.1)
				(type default)
			)
			(layer "B.Fab")
		)
		(fp_line
			(start -0.8636 -0.4572)
			(end -0.8636 -0.4064)
			(stroke
				(width 0.1)
				(type default)
			)
			(layer "B.Fab")
		)
		(fp_line
			(start -1.1938 0.4064)
			(end -0.8636 0.4064)
			(stroke
				(width 0.1)
				(type default)
			)
			(layer "B.Fab")
		)
		(fp_line
			(start -1.1938 -0.4064)
			(end -1.1938 0.4064)
			(stroke
				(width 0.1)
				(type default)
			)
			(layer "B.Fab")
		)
		(pad "1" smd rect
			(at 0.7366 0 90)
			(size 0.7112 0.8128)
			(layers "B.Cu" "B.Mask" "B.Paste")
			(net "P1V05_PCH_AUX")
		)
		(pad "2" smd rect
			(at -0.7366 0 90)
			(size 0.7112 0.8128)
			(layers "B.Cu" "B.Mask" "B.Paste")
			(net "GND")
		)
	)
)
